(kicad_pcb
	(version 20241229)
	(generator "pcbnew")
	(generator_version "9.0")
	(general
		(thickness 1.62)
		(legacy_teardrops no)
	)
	(paper "A3")
	(title_block
		(title "COM Express 7 Baseboard")
		(date "2025-02-04")
		(rev "1.1.2")
		(company "Antmicro Ltd")
		(comment 1 "www.antmicro.com")
		(comment 9 "footprints 155-158 of 802")
	)
	(layers
		(0 "F.Cu" signal)
		(4 "In1.Cu" signal)
		(6 "In2.Cu" signal)
		(8 "In3.Cu" signal)
		(10 "In4.Cu" signal)
		(12 "In5.Cu" signal)
		(14 "In6.Cu" signal)
		(2 "B.Cu" signal)
		(9 "F.Adhes" user "F.Adhesive")
		(11 "B.Adhes" user "B.Adhesive")
		(13 "F.Paste" user)
		(15 "B.Paste" user)
		(5 "F.SilkS" user "F.Silkscreen")
		(7 "B.SilkS" user "B.Silkscreen")
		(1 "F.Mask" user)
		(3 "B.Mask" user)
		(17 "Dwgs.User" user "User.Drawings")
		(19 "Cmts.User" user "User.Comments")
		(21 "Eco1.User" user "User.Eco1")
		(23 "Eco2.User" user "User.Eco2")
		(25 "Edge.Cuts" user)
		(27 "Margin" user)
		(31 "F.CrtYd" user "F.Courtyard")
		(29 "B.CrtYd" user "B.Courtyard")
		(35 "F.Fab" user)
		(33 "B.Fab" user)
	)
	(footprint "antmicro-footprints:QFN-16-1EP_4x4mm_P0.65mm"
		(layer "F.Cu")
		(at 115.159999 75.825 -90)
		(property "Reference" "U6"
			(at -2.365 0.709999 180)
			(layer "F.SilkS")
			(effects
				(font
					(size 0.7 0.7)
					(thickness 0.15)
				)
				(justify right bottom)
			)
		)
		(property "Value" "FT230X_QFN"
			(at 0 3.3 90)
			(layer "F.Fab")
			(effects
				(font
					(size 0.7 0.7)
					(thickness 0.15)
				)
				(justify right bottom)
			)
		)
		(property "Datasheet" "https://ftdichip.com/wp-content/uploads/2021/10/DS_FT230X.pdf"
			(at 0 0 270)
			(layer "F.Fab")
			(hide yes)
			(effects
				(font
					(size 1.27 1.27)
					(thickness 0.15)
				)
			)
		)
		(property "Author" "Antmicro"
			(at 39.334999 190.984999 0)
			(layer "F.Fab")
			(hide yes)
			(effects
				(font
					(size 1 1)
					(thickness 0.15)
				)
			)
		)
		(property "License" "Apache-2.0"
			(at 39.334999 190.984999 0)
			(layer "F.Fab")
			(hide yes)
			(effects
				(font
					(size 1 1)
					(thickness 0.15)
				)
			)
		)
		(property "MPN" "FT230XQ-R"
			(at 39.334999 190.984999 0)
			(layer "F.Fab")
			(hide yes)
			(effects
				(font
					(size 1 1)
					(thickness 0.15)
				)
			)
		)
		(property "Manufacturer" "FTDI Chip"
			(at 39.334999 190.984999 0)
			(layer "F.Fab")
			(hide yes)
			(effects
				(font
					(size 1 1)
					(thickness 0.15)
				)
			)
		)
		(sheetname "USB-C console")
		(sheetfile "usb-c_console.kicad_sch")
		(attr smd)
		(fp_line
			(start -2.101 2.1)
			(end -1.5 2.1)
			(stroke
				(width 0.15)
				(type solid)
			)
			(layer "F.SilkS")
		)
		(fp_line
			(start 1.499 2.1)
			(end 2.1 2.1)
			(stroke
				(width 0.15)
				(type solid)
			)
			(layer "F.SilkS")
		)
		(fp_line
			(start 2.1 2.1)
			(end 2.1 1.398)
			(stroke
				(width 0.15)
				(type solid)
			)
			(layer "F.SilkS")
		)
		(fp_line
			(start -2.101 1.398)
			(end -2.101 2.1)
			(stroke
				(width 0.15)
				(type solid)
			)
			(layer "F.SilkS")
		)
		(fp_line
			(start -2.1 -2.1)
			(end -2.101 -1.4)
			(stroke
				(width 0.15)
				(type solid)
			)
			(layer "F.SilkS")
		)
		(fp_line
			(start -1.4 -2.1)
			(end -2.1 -2.1)
			(stroke
				(width 0.15)
				(type solid)
			)
			(layer "F.SilkS")
		)
		(fp_line
			(start 1.499 -2.101)
			(end 2.1 -2.101)
			(stroke
				(width 0.15)
				(type solid)
			)
			(layer "F.SilkS")
		)
		(fp_line
			(start 2.1 -2.101)
			(end 2.1 -1.401)
			(stroke
				(width 0.15)
				(type solid)
			)
			(layer "F.SilkS")
		)
		(fp_circle
			(center -2.35 -1.4)
			(end -2.3 -1.4)
			(stroke
				(width 0.15)
				(type solid)
			)
			(fill yes)
			(layer "F.SilkS")
		)
		(fp_rect
			(start -2.35 -2.35)
			(end 2.35 2.35)
			(stroke
				(width 0.05)
				(type solid)
			)
			(fill no)
			(layer "F.CrtYd")
		)
		(fp_line
			(start -1.5 -2)
			(end -2 -1.5)
			(stroke
				(width 0.15)
				(type solid)
			)
			(layer "F.Fab")
		)
		(fp_rect
			(start 2 2)
			(end -2 -2)
			(stroke
				(width 0.15)
				(type solid)
			)
			(fill no)
			(layer "F.Fab")
		)
		(pad "1" smd rect
			(at -1.9 -0.975 270)
			(size 0.8 0.4)
			(layers "F.Cu" "F.Mask" "F.Paste")
			(net 57 "/USB-C console/FTDI_VCCIO")
			(pinfunction "V_{CCIO}")
			(pintype "power_in")
			(teardrops
				(best_length_ratio 0.2)
				(max_length 1)
				(best_width_ratio 0.9)
				(max_width 2)
				(curved_edges yes)
				(filter_ratio 0.9)
				(enabled yes)
				(allow_two_segments yes)
				(prefer_zone_connections yes)
			)
		)
		(pad "2" smd rect
			(at -1.9 -0.325 270)
			(size 0.8 0.4)
			(layers "F.Cu" "F.Mask" "F.Paste")
			(net 699 "/USB-C console/FTDI_RX")
			(pinfunction "RXD")
			(pintype "input")
			(teardrops
				(best_length_ratio 0.2)
				(max_length 1)
				(best_width_ratio 0.9)
				(max_width 2)
				(curved_edges yes)
				(filter_ratio 0.9)
				(enabled yes)
				(allow_two_segments yes)
				(prefer_zone_connections yes)
			)
		)
		(pad "3" smd rect
			(at -1.9 0.325 270)
			(size 0.8 0.4)
			(layers "F.Cu" "F.Mask" "F.Paste")
			(net 1 "GND")
			(pinfunction "GND")
			(pintype "passive")
			(teardrops
				(best_length_ratio 0.2)
				(max_length 1)
				(best_width_ratio 0.9)
				(max_width 2)
				(curved_edges yes)
				(filter_ratio 0.9)
				(enabled yes)
				(allow_two_segments yes)
				(prefer_zone_connections yes)
			)
		)
		(pad "4" smd rect
			(at -1.9 0.975 270)
			(size 0.8 0.4)
			(layers "F.Cu" "F.Mask" "F.Paste")
			(net 769 "unconnected-(U6-~{CTS}-Pad4)")
			(pinfunction "~{CTS}")
			(pintype "input+no_connect")
			(teardrops
				(best_length_ratio 0.2)
				(max_length 1)
				(best_width_ratio 0.9)
				(max_width 2)
				(curved_edges yes)
				(filter_ratio 0.9)
				(enabled yes)
				(allow_two_segments yes)
				(prefer_zone_connections yes)
			)
		)
		(pad "5" smd rect
			(at -0.975 1.9 270)
			(size 0.4 0.8)
			(layers "F.Cu" "F.Mask" "F.Paste")
			(net 128 "/USB-C console/FTDI_LED_TX")
			(pinfunction "CBUS2")
			(pintype "bidirectional")
			(teardrops
				(best_length_ratio 0.2)
				(max_length 1)
				(best_width_ratio 0.9)
				(max_width 2)
				(curved_edges yes)
				(filter_ratio 0.9)
				(enabled yes)
				(allow_two_segments yes)
				(prefer_zone_connections yes)
			)
		)
		(pad "6" smd rect
			(at -0.325 1.9 270)
			(size 0.4 0.8)
			(layers "F.Cu" "F.Mask" "F.Paste")
			(net 568 "/USB-C console/FTDI_D+")
			(pinfunction "D+")
			(pintype "input")
			(teardrops
				(best_length_ratio 0.2)
				(max_length 1)
				(best_width_ratio 0.9)
				(max_width 2)
				(curved_edges yes)
				(filter_ratio 0.9)
				(enabled yes)
				(allow_two_segments yes)
				(prefer_zone_connections yes)
			)
		)
		(pad "7" smd rect
			(at 0.325 1.9 270)
			(size 0.4 0.8)
			(layers "F.Cu" "F.Mask" "F.Paste")
			(net 569 "/USB-C console/FTDI_D-")
			(pinfunction "D-")
			(pintype "input")
			(teardrops
				(best_length_ratio 0.2)
				(max_length 1)
				(best_width_ratio 0.9)
				(max_width 2)
				(curved_edges yes)
				(filter_ratio 0.9)
				(enabled yes)
				(allow_two_segments yes)
				(prefer_zone_connections yes)
			)
		)
		(pad "8" smd rect
			(at 0.975 1.9 270)
			(size 0.4 0.8)
			(layers "F.Cu" "F.Mask" "F.Paste")
			(net 57 "/USB-C console/FTDI_VCCIO")
			(pinfunction "3V3_{OUT}")
			(pintype "passive")
			(teardrops
				(best_length_ratio 0.2)
				(max_length 1)
				(best_width_ratio 0.9)
				(max_width 2)
				(curved_edges yes)
				(filter_ratio 0.9)
				(enabled yes)
				(allow_two_segments yes)
				(prefer_zone_connections yes)
			)
		)
		(pad "9" smd rect
			(at 1.9 0.975 270)
			(size 0.8 0.4)
			(layers "F.Cu" "F.Mask" "F.Paste")
			(net 570 "Net-(U6-~{RESET})")
			(pinfunction "~{RESET}")
			(pintype "input")
			(teardrops
				(best_length_ratio 0.2)
				(max_length 1)
				(best_width_ratio 0.9)
				(max_width 2)
				(curved_edges yes)
				(filter_ratio 0.9)
				(enabled yes)
				(allow_two_segments yes)
				(prefer_zone_connections yes)
			)
		)
		(pad "10" smd rect
			(at 1.9 0.325 270)
			(size 0.8 0.4)
			(layers "F.Cu" "F.Mask" "F.Paste")
			(net 58 "/USB-C console/VBUS_FTDI")
			(pinfunction "V_{CC}")
			(pintype "power_in")
			(teardrops
				(best_length_ratio 0.2)
				(max_length 1)
				(best_width_ratio 0.9)
				(max_width 2)
				(curved_edges yes)
				(filter_ratio 0.9)
				(enabled yes)
				(allow_two_segments yes)
				(prefer_zone_connections yes)
			)
		)
		(pad "11" smd rect
			(at 1.9 -0.325 270)
			(size 0.8 0.4)
			(layers "F.Cu" "F.Mask" "F.Paste")
			(net 127 "/USB-C console/FTDI_LED_RX")
			(pinfunction "CBUS1")
			(pintype "bidirectional")
			(teardrops
				(best_length_ratio 0.2)
				(max_length 1)
				(best_width_ratio 0.9)
				(max_width 2)
				(curved_edges yes)
				(filter_ratio 0.9)
				(enabled yes)
				(allow_two_segments yes)
				(prefer_zone_connections yes)
			)
		)
		(pad "12" smd rect
			(at 1.9 -0.975 270)
			(size 0.8 0.4)
			(layers "F.Cu" "F.Mask" "F.Paste")
			(net 701 "/USB-C console/FTDI_CBUS0")
			(pinfunction "CBUS0")
			(pintype "bidirectional")
			(teardrops
				(best_length_ratio 0.2)
				(max_length 1)
				(best_width_ratio 0.9)
				(max_width 2)
				(curved_edges yes)
				(filter_ratio 0.9)
				(enabled yes)
				(allow_two_segments yes)
				(prefer_zone_connections yes)
			)
		)
		(pad "13" smd rect
			(at 0.975 -1.9 270)
			(size 0.4 0.8)
			(layers "F.Cu" "F.Mask" "F.Paste")
			(net 1 "GND")
			(pinfunction "GND")
			(pintype "power_in")
			(teardrops
				(best_length_ratio 0.2)
				(max_length 1)
				(best_width_ratio 0.9)
				(max_width 2)
				(curved_edges yes)
				(filter_ratio 0.9)
				(enabled no)
				(allow_two_segments yes)
				(prefer_zone_connections yes)
			)
		)
		(pad "14" smd rect
			(at 0.325 -1.9 270)
			(size 0.4 0.8)
			(layers "F.Cu" "F.Mask" "F.Paste")
			(net 702 "/USB-C console/FTDI_CBUS3")
			(pinfunction "CBUS3")
			(pintype "bidirectional")
			(teardrops
				(best_length_ratio 0.2)
				(max_length 1)
				(best_width_ratio 0.9)
				(max_width 2)
				(curved_edges yes)
				(filter_ratio 0.9)
				(enabled yes)
				(allow_two_segments yes)
				(prefer_zone_connections yes)
			)
		)
		(pad "15" smd rect
			(at -0.325 -1.9 270)
			(size 0.4 0.8)
			(layers "F.Cu" "F.Mask" "F.Paste")
			(net 700 "/USB-C console/FTDI_TX")
			(pinfunction "TXD")
			(pintype "output")
			(teardrops
				(best_length_ratio 0.2)
				(max_length 1)
				(best_width_ratio 0.9)
				(max_width 2)
				(curved_edges yes)
				(filter_ratio 0.9)
				(enabled yes)
				(allow_two_segments yes)
				(prefer_zone_connections yes)
			)
		)
		(pad "16" smd rect
			(at -0.975 -1.9 270)
			(size 0.4 0.8)
			(layers "F.Cu" "F.Mask" "F.Paste")
			(net 770 "unconnected-(U6-~{RTS}-Pad16)")
			(pinfunction "~{RTS}")
			(pintype "output+no_connect")
			(teardrops
				(best_length_ratio 0.2)
				(max_length 1)
				(best_width_ratio 0.9)
				(max_width 2)
				(curved_edges yes)
				(filter_ratio 0.9)
				(enabled yes)
				(allow_two_segments yes)
				(prefer_zone_connections yes)
			)
		)
		(pad "17" smd rect
			(at 0 0 270)
			(size 2.3 2.3)
			(layers "F.Cu" "F.Mask" "F.Paste")
			(net 1 "GND")
			(pinfunction "GND")
			(pintype "passive")
			(teardrops
				(best_length_ratio 0.2)
				(max_length 1)
				(best_width_ratio 0.9)
				(max_width 2)
				(curved_edges yes)
				(filter_ratio 0.9)
				(enabled no)
				(allow_two_segments yes)
				(prefer_zone_connections yes)
			)
		)
	)
	(footprint "antmicro-footprints:R_0201"
		(layer "F.Cu")
		(at 153.33 147.935 -90)
		(descr "Resistor SMD 0201")
		(tags "resistor SMD 0201")
		(property "Reference" "R249"
			(at 6.495 -0.57 270)
			(layer "F.SilkS")
			(effects
				(font
					(size 0.7 0.7)
					(thickness 0.15)
				)
				(justify left bottom)
			)
		)
		(property "Value" "R_0R_0201"
			(at 0 1.25 270)
			(layer "F.Fab")
			(effects
				(font
					(size 0.7 0.7)
					(thickness 0.15)
				)
				(justify left bottom)
			)
		)
		(property "Datasheet" "https://www.bourns.com/docs/product-datasheets/cr.pdf"
			(at 0 0 270)
			(layer "F.Fab")
			(hide yes)
			(effects
				(font
					(size 1.27 1.27)
					(thickness 0.15)
				)
			)
		)
		(property "Author" "Antmicro"
			(at 5.395 301.265 0)
			(layer "F.Fab")
			(hide yes)
			(effects
				(font
					(size 1 1)
					(thickness 0.15)
				)
			)
		)
		(property "License" "Apache-2.0"
			(at 5.395 301.265 0)
			(layer "F.Fab")
			(hide yes)
			(effects
				(font
					(size 1 1)
					(thickness 0.15)
				)
			)
		)
		(property "MPN" "CR0201-FX-0R00GLF"
			(at 5.395 301.265 0)
			(layer "F.Fab")
			(hide yes)
			(effects
				(font
					(size 1 1)
					(thickness 0.15)
				)
			)
		)
		(property "Manufacturer" "Bourns"
			(at 5.395 301.265 0)
			(layer "F.Fab")
			(hide yes)
			(effects
				(font
					(size 1 1)
					(thickness 0.15)
				)
			)
		)
		(property "Tolerance" "1%"
			(at 5.395 301.265 0)
			(layer "F.Fab")
			(hide yes)
			(effects
				(font
					(size 1 1)
					(thickness 0.15)
				)
			)
		)
		(property "Val" "0R"
			(at 5.395 301.265 0)
			(layer "F.Fab")
			(hide yes)
			(effects
				(font
					(size 1 1)
					(thickness 0.15)
				)
			)
		)
		(sheetname "KR to SFI #1")
		(sheetfile "kr_sfi.kicad_sch")
		(attr smd dnp)
		(fp_rect
			(start -0.7 -0.35)
			(end 0.7 0.35)
			(stroke
				(width 0.05)
				(type default)
			)
			(fill no)
			(layer "F.CrtYd")
		)
		(fp_rect
			(start -0.3 -0.15)
			(end 0.298 0.148)
			(stroke
				(width 0.15)
				(type solid)
			)
			(fill no)
			(layer "F.Fab")
		)
		(pad "" smd roundrect
			(at -0.346 0 270)
			(size 0.318 0.36)
			(layers "F.Paste")
			(roundrect_rratio 0.25)
			(teardrops
				(best_length_ratio 0.2)
				(max_length 1)
				(best_width_ratio 0.9)
				(max_width 2)
				(curved_edges yes)
				(filter_ratio 0.9)
				(enabled yes)
				(allow_two_segments yes)
				(prefer_zone_connections yes)
			)
		)
		(pad "" smd roundrect
			(at 0.344 0 270)
			(size 0.318 0.36)
			(layers "F.Paste")
			(roundrect_rratio 0.25)
			(teardrops
				(best_length_ratio 0.2)
				(max_length 1)
				(best_width_ratio 0.9)
				(max_width 2)
				(curved_edges yes)
				(filter_ratio 0.9)
				(enabled yes)
				(allow_two_segments yes)
				(prefer_zone_connections yes)
			)
		)
		(pad "1" smd roundrect
			(at -0.32 0 270)
			(size 0.46 0.4)
			(layers "F.Cu" "F.Mask")
			(roundrect_rratio 0.25)
			(net 432 "/2xSFP+/10GKR_SFP0.RX+")
			(pintype "passive")
			(teardrops
				(best_length_ratio 0.2)
				(max_length 1)
				(best_width_ratio 0.9)
				(max_width 2)
				(curved_edges yes)
				(filter_ratio 0.9)
				(enabled yes)
				(allow_two_segments yes)
				(prefer_zone_connections yes)
			)
		)
		(pad "2" smd roundrect
			(at 0.32 0 270)
			(size 0.46 0.4)
			(layers "F.Cu" "F.Mask")
			(roundrect_rratio 0.25)
			(net 946 "/2xSFP+/KR to SFI #1/BYP_RX+")
			(pintype "passive")
			(teardrops
				(best_length_ratio 0.2)
				(max_length 1)
				(best_width_ratio 0.9)
				(max_width 2)
				(curved_edges yes)
				(filter_ratio 0.9)
				(enabled yes)
				(allow_two_segments yes)
				(prefer_zone_connections yes)
			)
		)
	)
	(footprint "antmicro-footprints:R_0402_1005Metric"
		(layer "F.Cu")
		(at 156.475 72.31 180)
		(descr "Resistor SMD 0402")
		(tags "resistor SMD 0402")
		(property "Reference" "R134"
			(at -3.65 -0.45 0)
			(layer "F.SilkS")
			(effects
				(font
					(size 0.7 0.7)
					(thickness 0.15)
				)
				(justify right bottom)
			)
		)
		(property "Value" "R_0R_0402"
			(at -1.011843 1.772047 0)
			(layer "F.Fab")
			(effects
				(font
					(size 0.7 0.7)
					(thickness 0.15)
				)
				(justify right bottom)
			)
		)
		(property "Datasheet" "https://industrial.panasonic.com/cdbs/www-data/pdf/RDA0000/AOA0000C301.pdf"
			(at 0 0 180)
			(layer "F.Fab")
			(hide yes)
			(effects
				(font
					(size 1.27 1.27)
					(thickness 0.15)
				)
			)
		)
		(property "Author" "Antmicro"
			(at 312.95 144.62 0)
			(layer "F.Fab")
			(hide yes)
			(effects
				(font
					(size 1 1)
					(thickness 0.15)
				)
			)
		)
		(property "Current" "1A"
			(at 312.95 144.62 0)
			(layer "F.Fab")
			(hide yes)
			(effects
				(font
					(size 1 1)
					(thickness 0.15)
				)
			)
		)
		(property "License" "Apache-2.0"
			(at 312.95 144.62 0)
			(layer "F.Fab")
			(hide yes)
			(effects
				(font
					(size 1 1)
					(thickness 0.15)
				)
			)
		)
		(property "MPN" "ERJ2GE0R00X"
			(at 312.95 144.62 0)
			(layer "F.Fab")
			(hide yes)
			(effects
				(font
					(size 1 1)
					(thickness 0.15)
				)
			)
		)
		(property "Manufacturer" "Panasonic"
			(at 312.95 144.62 0)
			(layer "F.Fab")
			(hide yes)
			(effects
				(font
					(size 1 1)
					(thickness 0.15)
				)
			)
		)
		(property "Public" "False"
			(at 312.95 144.62 0)
			(layer "F.Fab")
			(hide yes)
			(effects
				(font
					(size 1 1)
					(thickness 0.15)
				)
			)
		)
		(property "Tolerance" ""
			(at 312.95 144.62 0)
			(layer "F.Fab")
			(hide yes)
			(effects
				(font
					(size 1 1)
					(thickness 0.15)
				)
			)
		)
		(property "Val" "0R"
			(at 312.95 144.62 0)
			(layer "F.Fab")
			(hide yes)
			(effects
				(font
					(size 1 1)
					(thickness 0.15)
				)
			)
		)
		(sheetname "M.2 key E")
		(sheetfile "m2keye.kicad_sch")
		(attr smd)
		(fp_rect
			(start -0.925 -0.47)
			(end 0.925 0.47)
			(stroke
				(width 0.05)
				(type default)
			)
			(fill no)
			(layer "F.CrtYd")
		)
		(fp_rect
			(start -0.5 -0.25)
			(end 0.5 0.25)
			(stroke
				(width 0.15)
				(type solid)
			)
			(fill no)
			(layer "F.Fab")
		)
		(pad "1" smd roundrect
			(at -0.48 0 180)
			(size 0.59 0.64)
			(layers "F.Cu" "F.Mask" "F.Paste")
			(roundrect_rratio 0.25)
			(net 377 "/Com Express 7 Interfaces/USB1.D-")
			(pintype "passive")
			(teardrops
				(best_length_ratio 0.2)
				(max_length 1)
				(best_width_ratio 0.9)
				(max_width 2)
				(curved_edges yes)
				(filter_ratio 0.9)
				(enabled yes)
				(allow_two_segments yes)
				(prefer_zone_connections yes)
			)
		)
		(pad "2" smd roundrect
			(at 0.48 0 180)
			(size 0.59 0.64)
			(layers "F.Cu" "F.Mask" "F.Paste")
			(roundrect_rratio 0.25)
			(net 4 "/M.2 key E/WIFI_BT_USB_D_N")
			(pintype "passive")
			(teardrops
				(best_length_ratio 0.2)
				(max_length 1)
				(best_width_ratio 0.9)
				(max_width 2)
				(curved_edges yes)
				(filter_ratio 0.9)
				(enabled yes)
				(allow_two_segments yes)
				(prefer_zone_connections yes)
			)
		)
	)
	(footprint "antmicro-footprints:TP_SMD_0.75mm"
		(layer "F.Cu")
		(at 118.25 74.71 90)
		(property "Reference" "TP8"
			(at 4.15 6.55 0)
			(layer "F.SilkS")
			(effects
				(font
					(size 0.7 0.7)
					(thickness 0.15)
				)
				(justify left bottom)
			)
		)
		(property "Value" "TP_0.75mm_SMD"
			(at 0 1.2 90)
			(layer "F.Fab")
			(effects
				(font
					(size 0.7 0.7)
					(thickness 0.15)
				)
				(justify left bottom)
			)
		)
		(property "Author" "Antmicro"
			(at 192.96 -43.54 0)
			(layer "F.Fab")
			(hide yes)
			(effects
				(font
					(size 1 1)
					(thickness 0.15)
				)
			)
		)
		(property "License" "Apache-2.0"
			(at 192.96 -43.54 0)
			(layer "F.Fab")
			(hide yes)
			(effects
				(font
					(size 1 1)
					(thickness 0.15)
				)
			)
		)
		(property "MPN" ""
			(at 192.96 -43.54 0)
			(layer "F.Fab")
			(hide yes)
			(effects
				(font
					(size 1 1)
					(thickness 0.15)
				)
			)
		)
		(property "Manufacturer" ""
			(at 192.96 -43.54 0)
			(layer "F.Fab")
			(hide yes)
			(effects
				(font
					(size 1 1)
					(thickness 0.15)
				)
			)
		)
		(property "Public" "False"
			(at 192.96 -43.54 0)
			(layer "F.Fab")
			(hide yes)
			(effects
				(font
					(size 1 1)
					(thickness 0.15)
				)
			)
		)
		(sheetname "USB-C console")
		(sheetfile "usb-c_console.kicad_sch")
		(attr exclude_from_pos_files exclude_from_bom)
		(fp_circle
			(center 0 0)
			(end 0.475 0)
			(stroke
				(width 0.05)
				(type default)
			)
			(fill no)
			(layer "F.CrtYd")
		)
		(pad "1" smd circle
			(at 0 0 90)
			(size 0.75 0.75)
			(layers "F.Cu" "F.Mask")
			(net 700 "/USB-C console/FTDI_TX")
			(pinfunction "1")
			(pintype "passive")
			(teardrops
				(best_length_ratio 0.4)
				(max_length 1)
				(best_width_ratio 0.9)
				(max_width 2)
				(curved_edges yes)
				(filter_ratio 0.9)
				(enabled yes)
				(allow_two_segments yes)
				(prefer_zone_connections yes)
			)
		)
	)
)
